FILE_TYPE = MACRO_DRAWING;
SET COLOR_WIRE YELLOW;
SET COLOR_PROP MONO;
SET COLOR_DOT WHITE;
SET COLOR_ARC YELLOW;
SET COLOR_BODY GREEN;
SET COLOR_NOTE MONO;
SET PROP_DISPLAY VALUE;
SET PAGE_NUMBER P254;
FORCEADD INTEL_CORP_BPAGE..1
(-1575 1875);
FORCEPROP 1 LAST CDS_CON_LAST_MODIFIED Fri Jun 16 17:49:35 2017
J 0
(-3000 2200);
PAINT ORANGE (-3000 2200);
DISPLAY INVISIBLE (-3000 2200);
FORCEPROP 2 LAST CUSTOM_TXT_CDS <XR_PAGE_TITLE>
J 0
(-9465 7125);
DISPLAY 0.638298 (-9465 7125);
PAINT PINK (-9465 7125);
DISPLAY INVISIBLE (-9465 7125);
FORCEPROP 2 LAST CUSTOM_TXT_CDS <CON_LAST_MODIFIED>
J 0
(-5575 1975);
PAINT ORANGE (-5575 1975);
FORCEPROP 2 LAST CUSTOM_TXT_CDS <CURRENT_DESIGN_SHEET> OF <TOTAL_DESIGN_SHEETS>
J 0
(-2025 1900);
PAINT ORANGE (-2025 1900);
FORCEPROP 1 LAST SCH_TITLE SMBUS BLOCK DIAGRAM - 1 OF 2
J 0
(-9525 1925);
DISPLAY 2.468085 (-9525 1925);
PAINT ORANGE (-9525 1925);
FORCEPROP 1 LAST COMMENT_BODY TRUE
J 0
(-1563 1887);
DISPLAY 0.468085 (-1563 1887);
PAINT GREEN (-1563 1887);
DISPLAY INVISIBLE (-1563 1887);
FORCEPROP 2 LAST CDS_LIB mstr_symbols
J 0
(-1575 1875);
PAINT MONO (-1575 1875);
DISPLAY INVISIBLE (-1575 1875);
FORCEPROP 2 LAST PAGE_BORDER TRUE
J 0
(-9465 7125);
DISPLAY 0.638298 (-9465 7125);
PAINT PINK (-9465 7125);
DISPLAY INVISIBLE (-9465 7125);
FORCEPROP 2 LAST CDS_XR_PAGE_TITLE CR-259 : @BASEBOARD_FAB2_LIB.BASEBOARD_FAB2(SCH_1):PAGE259
J 0
(-9465 7125);
DISPLAY 0.638298 (-9465 7125);
PAINT PINK (-9465 7125);
DISPLAY INVISIBLE (-9465 7125);
FORCENOTE
$CDS_IMAGE|SMBUS_Topology_NEW_20161004_2.jpg|5500|5500
(-5550 4325) 0;
DISPLAY LEFT (-5550 4325);
QUIT
